(kicad_pcb
	(version 20241229)
	(generator "pcbnew")
	(generator_version "9.0")
	(general
		(thickness 1.62)
		(legacy_teardrops no)
	)
	(paper "A3")
	(title_block
		(title "COM Express 7 Baseboard")
		(date "2025-02-04")
		(rev "1.1.2")
		(company "Antmicro Ltd")
		(comment 1 "www.antmicro.com")
		(comment 9 "footprint 253 of 802 (J2), pads 41-55 of 55")
	)
	(layers
		(0 "F.Cu" signal)
		(4 "In1.Cu" signal)
		(6 "In2.Cu" signal)
		(8 "In3.Cu" signal)
		(10 "In4.Cu" signal)
		(12 "In5.Cu" signal)
		(14 "In6.Cu" signal)
		(2 "B.Cu" signal)
		(9 "F.Adhes" user "F.Adhesive")
		(11 "B.Adhes" user "B.Adhesive")
		(13 "F.Paste" user)
		(15 "B.Paste" user)
		(5 "F.SilkS" user "F.Silkscreen")
		(7 "B.SilkS" user "B.Silkscreen")
		(1 "F.Mask" user)
		(3 "B.Mask" user)
		(17 "Dwgs.User" user "User.Drawings")
		(19 "Cmts.User" user "User.Comments")
		(21 "Eco1.User" user "User.Eco1")
		(23 "Eco2.User" user "User.Eco2")
		(25 "Edge.Cuts" user)
		(27 "Margin" user)
		(31 "F.CrtYd" user "F.Courtyard")
		(29 "B.CrtYd" user "B.Courtyard")
		(35 "F.Fab" user)
		(33 "B.Fab" user)
	)
	(footprint "antmicro-footprints:Conn_Bel-Fuse_SFP+_2x20_SS-79100-010"
		(locked yes)
		(layer "F.Cu")
		(at 142.55 162.31 -90)
		(property "Reference" "J2"
			(at 8.75 46.6 0)
			(unlocked yes)
			(layer "F.SilkS")
			(effects
				(font
					(size 0.7 0.7)
					(thickness 0.15)
				)
				(justify left bottom)
			)
		)
		(property "Value" "Bel-Fuse_SFP+_2x20_SS-79100-010"
			(at 9.45 1.2 270)
			(unlocked yes)
			(layer "F.Fab")
			(effects
				(font
					(size 0.7 0.7)
					(thickness 0.15)
				)
				(justify left bottom)
			)
		)
		(property "Datasheet" "https://www.belfuse.com/resources/datasheets/stewartconnector/ds-STW-SFP-cages.pdf"
			(at 0 0 270)
			(layer "F.Fab")
			(hide yes)
			(effects
				(font
					(size 1.27 1.27)
					(thickness 0.15)
				)
			)
		)
		(property "Author" "Antmicro"
			(at -19.76 304.86 0)
			(layer "F.Fab")
			(hide yes)
			(effects
				(font
					(size 1 1)
					(thickness 0.15)
				)
			)
		)
		(property "License" "Apache-2.0"
			(at -19.76 304.86 0)
			(layer "F.Fab")
			(hide yes)
			(effects
				(font
					(size 1 1)
					(thickness 0.15)
				)
			)
		)
		(property "MPN" "SS-79100-010"
			(at -19.76 304.86 0)
			(layer "F.Fab")
			(hide yes)
			(effects
				(font
					(size 1 1)
					(thickness 0.15)
				)
			)
		)
		(property "Manufacturer" "Bel Fuse"
			(at -19.76 304.86 0)
			(layer "F.Fab")
			(hide yes)
			(effects
				(font
					(size 1 1)
					(thickness 0.15)
				)
			)
		)
		(sheetname "2xSFP+")
		(sheetfile "2xSFP+.kicad_sch")
		(attr through_hole)
		(pad "T6" thru_hole circle
			(at 0.6 -2.2 270)
			(size 0.86 0.86)
			(drill 0.46)
			(layers "*.Cu" "*.Mask")
			(remove_unused_layers no)
			(net 166 "Net-(J2A-MOD_{ABS})")
			(pinfunction "MOD_{ABS}")
			(pintype "passive")
			(teardrops
				(best_length_ratio 0.4)
				(max_length 1)
				(best_width_ratio 0.9)
				(max_width 2)
				(curved_edges yes)
				(filter_ratio 0.9)
				(enabled yes)
				(allow_two_segments yes)
				(prefer_zone_connections yes)
			)
		)
		(pad "T7" thru_hole circle
			(at 1.4 -3.58 270)
			(size 0.86 0.86)
			(drill 0.46)
			(layers "*.Cu" "*.Mask")
			(remove_unused_layers no)
			(net 167 "Net-(J2A-RS0)")
			(pinfunction "RS0")
			(pintype "input")
			(teardrops
				(best_length_ratio 0.4)
				(max_length 1)
				(best_width_ratio 0.9)
				(max_width 2)
				(curved_edges yes)
				(filter_ratio 0.9)
				(enabled yes)
				(allow_two_segments yes)
				(prefer_zone_connections yes)
			)
		)
		(pad "T8" thru_hole circle
			(at 2.2 -2.2 270)
			(size 0.86 0.86)
			(drill 0.46)
			(layers "*.Cu" "*.Mask")
			(remove_unused_layers no)
			(net 168 "Net-(J2A-RX_{LOS})")
			(pinfunction "RX_{LOS}")
			(pintype "open_collector")
			(teardrops
				(best_length_ratio 0.4)
				(max_length 1)
				(best_width_ratio 0.9)
				(max_width 2)
				(curved_edges yes)
				(filter_ratio 0.9)
				(enabled yes)
				(allow_two_segments yes)
				(prefer_zone_connections yes)
			)
		)
		(pad "T9" thru_hole circle
			(at 3 -3.58 270)
			(size 0.86 0.86)
			(drill 0.46)
			(layers "*.Cu" "*.Mask")
			(remove_unused_layers no)
			(net 169 "Net-(J2A-RS1)")
			(pinfunction "RS1")
			(pintype "input")
			(teardrops
				(best_length_ratio 0.4)
				(max_length 1)
				(best_width_ratio 0.9)
				(max_width 2)
				(curved_edges yes)
				(filter_ratio 0.9)
				(enabled yes)
				(allow_two_segments yes)
				(prefer_zone_connections yes)
			)
		)
		(pad "T10" thru_hole circle
			(at 3.8 -2.2)
			(size 0.86 0.86)
			(drill 0.46)
			(layers "*.Cu" "*.Mask")
			(remove_unused_layers no)
			(net 1 "GND")
			(pinfunction "V_{EE}(R)")
			(pintype "passive")
			(teardrops
				(best_length_ratio 0.4)
				(max_length 1)
				(best_width_ratio 0.9)
				(max_width 2)
				(curved_edges yes)
				(filter_ratio 0.9)
				(enabled yes)
				(allow_two_segments yes)
				(prefer_zone_connections yes)
			)
		)
		(pad "T11" thru_hole circle
			(at 3.4 -5.13 270)
			(size 0.86 0.86)
			(drill 0.46)
			(layers "*.Cu" "*.Mask")
			(remove_unused_layers no)
			(net 1 "GND")
			(pinfunction "V_{EE}(R)")
			(pintype "passive")
			(teardrops
				(best_length_ratio 0.4)
				(max_length 1)
				(best_width_ratio 0.9)
				(max_width 2)
				(curved_edges yes)
				(filter_ratio 0.9)
				(enabled yes)
				(allow_two_segments yes)
				(prefer_zone_connections yes)
			)
		)
		(pad "T12" thru_hole circle
			(at 2.6 -6.52 270)
			(size 0.86 0.86)
			(drill 0.46)
			(layers "*.Cu" "*.Mask")
			(remove_unused_layers no)
			(net 170 "/2xSFP+/SFI0.RX-")
			(pinfunction "RD-")
			(pintype "output")
			(teardrops
				(best_length_ratio 0.4)
				(max_length 1)
				(best_width_ratio 0.9)
				(max_width 2)
				(curved_edges yes)
				(filter_ratio 0.9)
				(enabled yes)
				(allow_two_segments yes)
				(prefer_zone_connections yes)
			)
		)
		(pad "T13" thru_hole circle
			(at 1.8 -5.13 270)
			(size 0.86 0.86)
			(drill 0.46)
			(layers "*.Cu" "*.Mask")
			(remove_unused_layers no)
			(net 171 "/2xSFP+/SFI0.RX+")
			(pinfunction "RD+")
			(pintype "output")
			(teardrops
				(best_length_ratio 0.4)
				(max_length 1)
				(best_width_ratio 0.9)
				(max_width 2)
				(curved_edges yes)
				(filter_ratio 0.9)
				(enabled yes)
				(allow_two_segments yes)
				(prefer_zone_connections yes)
			)
		)
		(pad "T14" thru_hole circle
			(at 1 -6.52 270)
			(size 0.86 0.86)
			(drill 0.46)
			(layers "*.Cu" "*.Mask")
			(remove_unused_layers no)
			(net 1 "GND")
			(pinfunction "V_{EE}(R)")
			(pintype "passive")
			(teardrops
				(best_length_ratio 0.4)
				(max_length 1)
				(best_width_ratio 0.9)
				(max_width 2)
				(curved_edges yes)
				(filter_ratio 0.9)
				(enabled yes)
				(allow_two_segments yes)
				(prefer_zone_connections yes)
			)
		)
		(pad "T15" thru_hole circle
			(at 0.2 -5.13 270)
			(size 0.86 0.86)
			(drill 0.46)
			(layers "*.Cu" "*.Mask")
			(remove_unused_layers no)
			(net 2 "+3V3")
			(pinfunction "V_{CC}(R)")
			(pintype "power_in")
			(teardrops
				(best_length_ratio 0.4)
				(max_length 1)
				(best_width_ratio 0.9)
				(max_width 2)
				(curved_edges yes)
				(filter_ratio 0.9)
				(enabled yes)
				(allow_two_segments yes)
				(prefer_zone_connections yes)
			)
		)
		(pad "T16" thru_hole circle
			(at -0.6 -6.52 270)
			(size 0.86 0.86)
			(drill 0.46)
			(layers "*.Cu" "*.Mask")
			(remove_unused_layers no)
			(net 2 "+3V3")
			(pinfunction "V_{CC}(T)")
			(pintype "power_in")
			(teardrops
				(best_length_ratio 0.4)
				(max_length 1)
				(best_width_ratio 0.9)
				(max_width 2)
				(curved_edges yes)
				(filter_ratio 0.9)
				(enabled yes)
				(allow_two_segments yes)
				(prefer_zone_connections yes)
			)
		)
		(pad "T17" thru_hole circle
			(at -1.4 -5.13 270)
			(size 0.86 0.86)
			(drill 0.46)
			(layers "*.Cu" "*.Mask")
			(remove_unused_layers no)
			(net 1 "GND")
			(pinfunction "V_{EE}(T)")
			(pintype "passive")
			(teardrops
				(best_length_ratio 0.4)
				(max_length 1)
				(best_width_ratio 0.9)
				(max_width 2)
				(curved_edges yes)
				(filter_ratio 0.9)
				(enabled yes)
				(allow_two_segments yes)
				(prefer_zone_connections yes)
			)
		)
		(pad "T18" thru_hole circle
			(at -2.2 -6.52 270)
			(size 0.86 0.86)
			(drill 0.46)
			(layers "*.Cu" "*.Mask")
			(remove_unused_layers no)
			(net 172 "/2xSFP+/SFI0.TX+")
			(pinfunction "TD+")
			(pintype "input")
			(teardrops
				(best_length_ratio 0.4)
				(max_length 1)
				(best_width_ratio 0.9)
				(max_width 2)
				(curved_edges yes)
				(filter_ratio 0.9)
				(enabled yes)
				(allow_two_segments yes)
				(prefer_zone_connections yes)
			)
		)
		(pad "T19" thru_hole circle
			(at -3 -5.13 270)
			(size 0.86 0.86)
			(drill 0.46)
			(layers "*.Cu" "*.Mask")
			(remove_unused_layers no)
			(net 173 "/2xSFP+/SFI0.TX-")
			(pinfunction "TD-")
			(pintype "input")
			(teardrops
				(best_length_ratio 0.4)
				(max_length 1)
				(best_width_ratio 0.9)
				(max_width 2)
				(curved_edges yes)
				(filter_ratio 0.9)
				(enabled yes)
				(allow_two_segments yes)
				(prefer_zone_connections yes)
			)
		)
		(pad "T20" thru_hole circle
			(at -3.8 -6.52 270)
			(size 0.86 0.86)
			(drill 0.46)
			(layers "*.Cu" "*.Mask")
			(remove_unused_layers no)
			(net 1 "GND")
			(pinfunction "V_{EE}(T)")
			(pintype "passive")
			(teardrops
				(best_length_ratio 0.4)
				(max_length 1)
				(best_width_ratio 0.9)
				(max_width 2)
				(curved_edges yes)
				(filter_ratio 0.9)
				(enabled yes)
				(allow_two_segments yes)
				(prefer_zone_connections yes)
			)
		)
	)
)
